(kicad_pcb
	(version 20260206)
	(generator "pcbnew")
	(generator_version "10.0")
	(general
		(thickness 1.6)
		(legacy_teardrops no)
	)
	(paper "A4")
	(title_block
		(title "01162023_DA0F0TEBIF0_F0T_Expander_BD_F_brd_V02_OCP.brd")
		(comment 1 "Grand Teton / footprints 8700-8709 of 9728")
	)
	(layers
		(0 "F.Cu" signal "TOP")
		(4 "In1.Cu" signal "GND")
		(6 "In2.Cu" signal "VCC")
		(8 "In3.Cu" signal "VCC1")
		(10 "In4.Cu" signal "GND1")
		(12 "In5.Cu" signal "IN1")
		(14 "In6.Cu" signal "GND2")
		(16 "In7.Cu" signal "IN2")
		(18 "In8.Cu" signal "GND3")
		(20 "In9.Cu" signal "IN3")
		(22 "In10.Cu" signal "GND4")
		(24 "In11.Cu" signal "IN4")
		(26 "In12.Cu" signal "GND5")
		(28 "In13.Cu" signal "IN5")
		(30 "In14.Cu" signal "GND6")
		(32 "In15.Cu" signal "IN6")
		(34 "In16.Cu" signal "GND7")
		(2 "B.Cu" signal "BOTTOM")
		(9 "F.Adhes" user "F.Adhesive")
		(11 "B.Adhes" user "B.Adhesive")
		(13 "F.Paste" user "Package Geometry/Pastemask Top")
		(15 "B.Paste" user "Package Geometry/Pastemask Bottom")
		(5 "F.SilkS" user "Ref Des/Silkscreen Top")
		(7 "B.SilkS" user "Ref Des/Silkscreen Bottom")
		(1 "F.Mask" user "Board Geometry/Soldermask Top")
		(3 "B.Mask" user "Board Geometry/Soldermask Bottom")
		(17 "Dwgs.User" user "User.Drawings")
		(19 "Cmts.User" user "User.Comments")
		(21 "Eco1.User" user "User.Eco1")
		(23 "Eco2.User" user "User.Eco2")
		(25 "Edge.Cuts" user "Board Geometry/Outline")
		(27 "Margin" user)
		(31 "F.CrtYd" user "Package Geometry/Place Bound Top")
		(29 "B.CrtYd" user "Package Geometry/Place Bound Bottom")
		(35 "F.Fab" user "Ref Des/Assembly Top")
		(33 "B.Fab" user "Ref Des/Assembly Bottom")
	)
	(footprint ""
		(layer "B.Cu")
		(at 177.42027 -196.890386 180)
		(property "Reference" "R1030"
			(at 0 0 0)
			(layer "B.SilkS")
			(hide yes)
			(effects
				(font
					(size 1.27 1.27)
				)
				(justify mirror)
			)
		)
		(property "Value" ""
			(at 0 0 0)
			(layer "B.Fab")
			(effects
				(font
					(size 1.27 1.27)
				)
				(justify mirror)
			)
		)
		(duplicate_pad_numbers_are_jumpers no)
		(fp_line
			(start 0.7874 0.4064)
			(end 0.7874 -0.4064)
			(stroke
				(width 0.1524)
				(type default)
			)
			(layer "B.SilkS")
		)
		(fp_line
			(start 0.7874 -0.4064)
			(end -0.7874 -0.4064)
			(stroke
				(width 0.1524)
				(type default)
			)
			(layer "B.SilkS")
		)
		(fp_line
			(start -0.7874 0.4064)
			(end 0.7874 0.4064)
			(stroke
				(width 0.1524)
				(type default)
			)
			(layer "B.SilkS")
		)
		(fp_line
			(start -0.7874 -0.4064)
			(end -0.7874 0.4064)
			(stroke
				(width 0.1524)
				(type default)
			)
			(layer "B.SilkS")
		)
		(fp_line
			(start 0.67945 0.3048)
			(end 0.67945 -0.305054)
			(stroke
				(width 0.1)
				(type default)
			)
			(layer "B.Fab")
		)
		(fp_line
			(start 0.67945 -0.305054)
			(end 0.12065 -0.305054)
			(stroke
				(width 0.1)
				(type default)
			)
			(layer "B.Fab")
		)
		(fp_line
			(start 0.12065 0.3048)
			(end 0.67945 0.3048)
			(stroke
				(width 0.1)
				(type default)
			)
			(layer "B.Fab")
		)
		(fp_line
			(start 0.12065 0.2794)
			(end 0.12065 0.3048)
			(stroke
				(width 0.1)
				(type default)
			)
			(layer "B.Fab")
		)
		(fp_line
			(start 0.12065 -0.2794)
			(end -0.12065 -0.2794)
			(stroke
				(width 0.1)
				(type default)
			)
			(layer "B.Fab")
		)
		(fp_line
			(start 0.12065 -0.305054)
			(end 0.12065 -0.2794)
			(stroke
				(width 0.1)
				(type default)
			)
			(layer "B.Fab")
		)
		(fp_line
			(start -0.120396 0.3048)
			(end -0.120396 0.2794)
			(stroke
				(width 0.1)
				(type default)
			)
			(layer "B.Fab")
		)
		(fp_line
			(start -0.120396 0.2794)
			(end 0.12065 0.2794)
			(stroke
				(width 0.1)
				(type default)
			)
			(layer "B.Fab")
		)
		(fp_line
			(start -0.12065 -0.2794)
			(end -0.12065 -0.3048)
			(stroke
				(width 0.1)
				(type default)
			)
			(layer "B.Fab")
		)
		(fp_line
			(start -0.12065 -0.3048)
			(end -0.67945 -0.3048)
			(stroke
				(width 0.1)
				(type default)
			)
			(layer "B.Fab")
		)
		(fp_line
			(start -0.67945 0.3048)
			(end -0.120396 0.3048)
			(stroke
				(width 0.1)
				(type default)
			)
			(layer "B.Fab")
		)
		(fp_line
			(start -0.67945 -0.3048)
			(end -0.67945 0.3048)
			(stroke
				(width 0.1)
				(type default)
			)
			(layer "B.Fab")
		)
		(pad "1" smd circle
			(at 0.40005 0)
			(size 0 0)
			(layers "B.Cu" "B.Mask" "B.Paste")
			(net "SPI_BIC1_CLK_LS01_DIR2")
		)
		(pad "2" smd circle
			(at -0.40005 0)
			(size 0 0)
			(layers "B.Cu" "B.Mask" "B.Paste")
			(net "P1V8_PEX")
		)
	)
	(footprint ""
		(layer "B.Cu")
		(at 165.299898 -299.2755 180)
		(property "Reference" "C1392"
			(at 0 0 0)
			(layer "B.SilkS")
			(hide yes)
			(effects
				(font
					(size 1.27 1.27)
				)
				(justify mirror)
			)
		)
		(property "Value" ""
			(at 0 0 0)
			(layer "B.Fab")
			(effects
				(font
					(size 1.27 1.27)
				)
				(justify mirror)
			)
		)
		(duplicate_pad_numbers_are_jumpers no)
		(fp_line
			(start 0.299974 0.150114)
			(end 0.299974 -0.150114)
			(stroke
				(width 0.1)
				(type default)
			)
			(layer "B.Fab")
		)
		(fp_line
			(start 0.299974 -0.150114)
			(end -0.299974 -0.150114)
			(stroke
				(width 0.1)
				(type default)
			)
			(layer "B.Fab")
		)
		(fp_line
			(start -0.299974 0.150114)
			(end 0.299974 0.150114)
			(stroke
				(width 0.1)
				(type default)
			)
			(layer "B.Fab")
		)
		(fp_line
			(start -0.299974 -0.150114)
			(end -0.299974 0.150114)
			(stroke
				(width 0.1)
				(type default)
			)
			(layer "B.Fab")
		)
		(pad "1" smd rect
			(at 0.2667 0)
			(size 0.3048 0.381)
			(layers "B.Cu" "B.Mask" "B.Paste")
			(net "P0V8_PEX1")
		)
		(pad "2" smd rect
			(at -0.2667 0)
			(size 0.3048 0.381)
			(layers "B.Cu" "B.Mask" "B.Paste")
			(net "GND")
		)
	)
	(footprint ""
		(layer "B.Cu")
		(at 400.349974 -290.199826 90)
		(property "Reference" "C1941"
			(at 0 0 90)
			(layer "B.SilkS")
			(hide yes)
			(effects
				(font
					(size 1.27 1.27)
				)
				(justify mirror)
			)
		)
		(property "Value" ""
			(at 0 0 90)
			(layer "B.Fab")
			(effects
				(font
					(size 1.27 1.27)
				)
				(justify mirror)
			)
		)
		(duplicate_pad_numbers_are_jumpers no)
		(fp_line
			(start 0.299974 -0.150114)
			(end -0.299974 -0.150114)
			(stroke
				(width 0.1)
				(type default)
			)
			(layer "B.Fab")
		)
		(fp_line
			(start -0.299974 -0.150114)
			(end -0.299974 0.150114)
			(stroke
				(width 0.1)
				(type default)
			)
			(layer "B.Fab")
		)
		(fp_line
			(start 0.299974 0.150114)
			(end 0.299974 -0.150114)
			(stroke
				(width 0.1)
				(type default)
			)
			(layer "B.Fab")
		)
		(fp_line
			(start -0.299974 0.150114)
			(end 0.299974 0.150114)
			(stroke
				(width 0.1)
				(type default)
			)
			(layer "B.Fab")
		)
		(pad "1" smd rect
			(at 0.2667 0 270)
			(size 0.3048 0.381)
			(layers "B.Cu" "B.Mask" "B.Paste")
			(net "P0V8_SERDES_VDDA_PEX3")
		)
		(pad "2" smd rect
			(at -0.2667 0 270)
			(size 0.3048 0.381)
			(layers "B.Cu" "B.Mask" "B.Paste")
			(net "GND")
		)
	)
	(footprint ""
		(layer "B.Cu")
		(at 179.55006 -288.299906 90)
		(property "Reference" "C3109"
			(at 0 0 90)
			(layer "B.SilkS")
			(hide yes)
			(effects
				(font
					(size 1.27 1.27)
				)
				(justify mirror)
			)
		)
		(property "Value" ""
			(at 0 0 90)
			(layer "B.Fab")
			(effects
				(font
					(size 1.27 1.27)
				)
				(justify mirror)
			)
		)
		(duplicate_pad_numbers_are_jumpers no)
		(fp_line
			(start 0.299974 -0.150114)
			(end -0.299974 -0.150114)
			(stroke
				(width 0.1)
				(type default)
			)
			(layer "B.Fab")
		)
		(fp_line
			(start -0.299974 -0.150114)
			(end -0.299974 0.150114)
			(stroke
				(width 0.1)
				(type default)
			)
			(layer "B.Fab")
		)
		(fp_line
			(start 0.299974 0.150114)
			(end 0.299974 -0.150114)
			(stroke
				(width 0.1)
				(type default)
			)
			(layer "B.Fab")
		)
		(fp_line
			(start -0.299974 0.150114)
			(end 0.299974 0.150114)
			(stroke
				(width 0.1)
				(type default)
			)
			(layer "B.Fab")
		)
		(pad "1" smd rect
			(at 0.2667 0 270)
			(size 0.3048 0.381)
			(layers "B.Cu" "B.Mask" "B.Paste")
			(net "P1V25_PEX1")
		)
		(pad "2" smd rect
			(at -0.2667 0 270)
			(size 0.3048 0.381)
			(layers "B.Cu" "B.Mask" "B.Paste")
			(net "GND")
		)
	)
	(footprint ""
		(layer "B.Cu")
		(at 305.149758 -293.99992 180)
		(property "Reference" "C3298"
			(at 0 0 0)
			(layer "B.SilkS")
			(hide yes)
			(effects
				(font
					(size 1.27 1.27)
				)
				(justify mirror)
			)
		)
		(property "Value" ""
			(at 0 0 0)
			(layer "B.Fab")
			(effects
				(font
					(size 1.27 1.27)
				)
				(justify mirror)
			)
		)
		(duplicate_pad_numbers_are_jumpers no)
		(fp_line
			(start 0.299974 0.150114)
			(end 0.299974 -0.150114)
			(stroke
				(width 0.1)
				(type default)
			)
			(layer "B.Fab")
		)
		(fp_line
			(start 0.299974 -0.150114)
			(end -0.299974 -0.150114)
			(stroke
				(width 0.1)
				(type default)
			)
			(layer "B.Fab")
		)
		(fp_line
			(start -0.299974 0.150114)
			(end 0.299974 0.150114)
			(stroke
				(width 0.1)
				(type default)
			)
			(layer "B.Fab")
		)
		(fp_line
			(start -0.299974 -0.150114)
			(end -0.299974 0.150114)
			(stroke
				(width 0.1)
				(type default)
			)
			(layer "B.Fab")
		)
		(pad "1" smd rect
			(at 0.2667 0)
			(size 0.3048 0.381)
			(layers "B.Cu" "B.Mask" "B.Paste")
			(net "P1V25_SERDES_VDDPLL_PEX2")
		)
		(pad "2" smd rect
			(at -0.2667 0)
			(size 0.3048 0.381)
			(layers "B.Cu" "B.Mask" "B.Paste")
			(net "GND")
		)
	)
	(footprint ""
		(layer "B.Cu")
		(at 212.09 -198.755 90)
		(property "Reference" "R1528"
			(at 0 0 90)
			(layer "B.SilkS")
			(hide yes)
			(effects
				(font
					(size 1.27 1.27)
				)
				(justify mirror)
			)
		)
		(property "Value" ""
			(at 0 0 90)
			(layer "B.Fab")
			(effects
				(font
					(size 1.27 1.27)
				)
				(justify mirror)
			)
		)
		(duplicate_pad_numbers_are_jumpers no)
		(fp_line
			(start 0.7874 -0.4064)
			(end -0.7874 -0.4064)
			(stroke
				(width 0.1524)
				(type default)
			)
			(layer "B.SilkS")
		)
		(fp_line
			(start -0.7874 -0.4064)
			(end -0.7874 0.4064)
			(stroke
				(width 0.1524)
				(type default)
			)
			(layer "B.SilkS")
		)
		(fp_line
			(start 0.7874 0.4064)
			(end 0.7874 -0.4064)
			(stroke
				(width 0.1524)
				(type default)
			)
			(layer "B.SilkS")
		)
		(fp_line
			(start -0.7874 0.4064)
			(end 0.7874 0.4064)
			(stroke
				(width 0.1524)
				(type default)
			)
			(layer "B.SilkS")
		)
		(fp_line
			(start 0.67945 -0.305054)
			(end 0.12065 -0.305054)
			(stroke
				(width 0.1)
				(type default)
			)
			(layer "B.Fab")
		)
		(fp_line
			(start 0.12065 -0.305054)
			(end 0.12065 -0.2794)
			(stroke
				(width 0.1)
				(type default)
			)
			(layer "B.Fab")
		)
		(fp_line
			(start -0.12065 -0.3048)
			(end -0.67945 -0.3048)
			(stroke
				(width 0.1)
				(type default)
			)
			(layer "B.Fab")
		)
		(fp_line
			(start -0.67945 -0.3048)
			(end -0.67945 0.3048)
			(stroke
				(width 0.1)
				(type default)
			)
			(layer "B.Fab")
		)
		(fp_line
			(start 0.12065 -0.2794)
			(end -0.12065 -0.2794)
			(stroke
				(width 0.1)
				(type default)
			)
			(layer "B.Fab")
		)
		(fp_line
			(start -0.12065 -0.2794)
			(end -0.12065 -0.3048)
			(stroke
				(width 0.1)
				(type default)
			)
			(layer "B.Fab")
		)
		(fp_line
			(start 0.12065 0.2794)
			(end 0.12065 0.3048)
			(stroke
				(width 0.1)
				(type default)
			)
			(layer "B.Fab")
		)
		(fp_line
			(start -0.120396 0.2794)
			(end 0.12065 0.2794)
			(stroke
				(width 0.1)
				(type default)
			)
			(layer "B.Fab")
		)
		(fp_line
			(start 0.67945 0.3048)
			(end 0.67945 -0.305054)
			(stroke
				(width 0.1)
				(type default)
			)
			(layer "B.Fab")
		)
		(fp_line
			(start 0.12065 0.3048)
			(end 0.67945 0.3048)
			(stroke
				(width 0.1)
				(type default)
			)
			(layer "B.Fab")
		)
		(fp_line
			(start -0.120396 0.3048)
			(end -0.120396 0.2794)
			(stroke
				(width 0.1)
				(type default)
			)
			(layer "B.Fab")
		)
		(fp_line
			(start -0.67945 0.3048)
			(end -0.120396 0.3048)
			(stroke
				(width 0.1)
				(type default)
			)
			(layer "B.Fab")
		)
		(pad "1" smd circle
			(at 0.40005 0 270)
			(size 0 0)
			(layers "B.Cu" "B.Mask" "B.Paste")
			(net "SMB_NIC6_LS_R_SDA")
		)
		(pad "2" smd circle
			(at -0.40005 0 270)
			(size 0 0)
			(layers "B.Cu" "B.Mask" "B.Paste")
			(net "SMB_NIC6_R_SDA")
		)
	)
	(footprint ""
		(layer "B.Cu")
		(at 53.474874 -293.99992 -90)
		(property "Reference" "C1153"
			(at 0 0 90)
			(layer "B.SilkS")
			(hide yes)
			(effects
				(font
					(size 1.27 1.27)
				)
				(justify mirror)
			)
		)
		(property "Value" ""
			(at 0 0 90)
			(layer "B.Fab")
			(effects
				(font
					(size 1.27 1.27)
				)
				(justify mirror)
			)
		)
		(duplicate_pad_numbers_are_jumpers no)
		(fp_line
			(start -0.299974 0.150114)
			(end 0.299974 0.150114)
			(stroke
				(width 0.1)
				(type default)
			)
			(layer "B.Fab")
		)
		(fp_line
			(start 0.299974 0.150114)
			(end 0.299974 -0.150114)
			(stroke
				(width 0.1)
				(type default)
			)
			(layer "B.Fab")
		)
		(fp_line
			(start -0.299974 -0.150114)
			(end -0.299974 0.150114)
			(stroke
				(width 0.1)
				(type default)
			)
			(layer "B.Fab")
		)
		(fp_line
			(start 0.299974 -0.150114)
			(end -0.299974 -0.150114)
			(stroke
				(width 0.1)
				(type default)
			)
			(layer "B.Fab")
		)
		(pad "1" smd rect
			(at 0.2667 0 90)
			(size 0.3048 0.381)
			(layers "B.Cu" "B.Mask" "B.Paste")
			(net "P0V8_PEX0")
		)
		(pad "2" smd rect
			(at -0.2667 0 90)
			(size 0.3048 0.381)
			(layers "B.Cu" "B.Mask" "B.Paste")
			(net "GND")
		)
	)
	(footprint ""
		(layer "B.Cu")
		(at 290.42487 -293.99992 90)
		(property "Reference" "C1654"
			(at 0 0 90)
			(layer "B.SilkS")
			(hide yes)
			(effects
				(font
					(size 1.27 1.27)
				)
				(justify mirror)
			)
		)
		(property "Value" ""
			(at 0 0 90)
			(layer "B.Fab")
			(effects
				(font
					(size 1.27 1.27)
				)
				(justify mirror)
			)
		)
		(duplicate_pad_numbers_are_jumpers no)
		(fp_line
			(start 0.299974 -0.150114)
			(end -0.299974 -0.150114)
			(stroke
				(width 0.1)
				(type default)
			)
			(layer "B.Fab")
		)
		(fp_line
			(start -0.299974 -0.150114)
			(end -0.299974 0.150114)
			(stroke
				(width 0.1)
				(type default)
			)
			(layer "B.Fab")
		)
		(fp_line
			(start 0.299974 0.150114)
			(end 0.299974 -0.150114)
			(stroke
				(width 0.1)
				(type default)
			)
			(layer "B.Fab")
		)
		(fp_line
			(start -0.299974 0.150114)
			(end 0.299974 0.150114)
			(stroke
				(width 0.1)
				(type default)
			)
			(layer "B.Fab")
		)
		(pad "1" smd rect
			(at 0.2667 0 270)
			(size 0.3048 0.381)
			(layers "B.Cu" "B.Mask" "B.Paste")
			(net "P0V8_PEX2")
		)
		(pad "2" smd rect
			(at -0.2667 0 270)
			(size 0.3048 0.381)
			(layers "B.Cu" "B.Mask" "B.Paste")
			(net "GND")
		)
	)
	(footprint ""
		(layer "B.Cu")
		(at 229.556564 -208.78546 90)
		(property "Reference" "R5294"
			(at 0 0 90)
			(layer "B.SilkS")
			(hide yes)
			(effects
				(font
					(size 1.27 1.27)
				)
				(justify mirror)
			)
		)
		(property "Value" ""
			(at 0 0 90)
			(layer "B.Fab")
			(effects
				(font
					(size 1.27 1.27)
				)
				(justify mirror)
			)
		)
		(duplicate_pad_numbers_are_jumpers no)
		(fp_line
			(start 0.7874 -0.4064)
			(end -0.7874 -0.4064)
			(stroke
				(width 0.1524)
				(type default)
			)
			(layer "B.SilkS")
		)
		(fp_line
			(start -0.7874 -0.4064)
			(end -0.7874 0.4064)
			(stroke
				(width 0.1524)
				(type default)
			)
			(layer "B.SilkS")
		)
		(fp_line
			(start 0.7874 0.4064)
			(end 0.7874 -0.4064)
			(stroke
				(width 0.1524)
				(type default)
			)
			(layer "B.SilkS")
		)
		(fp_line
			(start -0.7874 0.4064)
			(end 0.7874 0.4064)
			(stroke
				(width 0.1524)
				(type default)
			)
			(layer "B.SilkS")
		)
		(fp_line
			(start 0.67945 -0.305054)
			(end 0.12065 -0.305054)
			(stroke
				(width 0.1)
				(type default)
			)
			(layer "B.Fab")
		)
		(fp_line
			(start 0.12065 -0.305054)
			(end 0.12065 -0.2794)
			(stroke
				(width 0.1)
				(type default)
			)
			(layer "B.Fab")
		)
		(fp_line
			(start -0.12065 -0.3048)
			(end -0.67945 -0.3048)
			(stroke
				(width 0.1)
				(type default)
			)
			(layer "B.Fab")
		)
		(fp_line
			(start -0.67945 -0.3048)
			(end -0.67945 0.3048)
			(stroke
				(width 0.1)
				(type default)
			)
			(layer "B.Fab")
		)
		(fp_line
			(start 0.12065 -0.2794)
			(end -0.12065 -0.2794)
			(stroke
				(width 0.1)
				(type default)
			)
			(layer "B.Fab")
		)
		(fp_line
			(start -0.12065 -0.2794)
			(end -0.12065 -0.3048)
			(stroke
				(width 0.1)
				(type default)
			)
			(layer "B.Fab")
		)
		(fp_line
			(start 0.12065 0.2794)
			(end 0.12065 0.3048)
			(stroke
				(width 0.1)
				(type default)
			)
			(layer "B.Fab")
		)
		(fp_line
			(start -0.120396 0.2794)
			(end 0.12065 0.2794)
			(stroke
				(width 0.1)
				(type default)
			)
			(layer "B.Fab")
		)
		(fp_line
			(start 0.67945 0.3048)
			(end 0.67945 -0.305054)
			(stroke
				(width 0.1)
				(type default)
			)
			(layer "B.Fab")
		)
		(fp_line
			(start 0.12065 0.3048)
			(end 0.67945 0.3048)
			(stroke
				(width 0.1)
				(type default)
			)
			(layer "B.Fab")
		)
		(fp_line
			(start -0.120396 0.3048)
			(end -0.120396 0.2794)
			(stroke
				(width 0.1)
				(type default)
			)
			(layer "B.Fab")
		)
		(fp_line
			(start -0.67945 0.3048)
			(end -0.120396 0.3048)
			(stroke
				(width 0.1)
				(type default)
			)
			(layer "B.Fab")
		)
		(pad "1" smd circle
			(at 0.40005 0 270)
			(size 0 0)
			(layers "B.Cu" "B.Mask" "B.Paste")
			(net "BIC_SEL_FLASH_SW1")
		)
		(pad "2" smd circle
			(at -0.40005 0 270)
			(size 0 0)
			(layers "B.Cu" "B.Mask" "B.Paste")
			(net "BIC_SEL_FLASH_SW1_R")
		)
	)
	(footprint ""
		(layer "B.Cu")
		(at 301.141384 -287.824926)
		(property "Reference" "C3345"
			(at 0 0 0)
			(layer "B.SilkS")
			(hide yes)
			(effects
				(font
					(size 1.27 1.27)
				)
				(justify mirror)
			)
		)
		(property "Value" ""
			(at 0 0 0)
			(layer "B.Fab")
			(effects
				(font
					(size 1.27 1.27)
				)
				(justify mirror)
			)
		)
		(duplicate_pad_numbers_are_jumpers no)
		(fp_line
			(start -0.299974 -0.150114)
			(end -0.299974 0.150114)
			(stroke
				(width 0.1)
				(type default)
			)
			(layer "B.Fab")
		)
		(fp_line
			(start -0.299974 0.150114)
			(end 0.299974 0.150114)
			(stroke
				(width 0.1)
				(type default)
			)
			(layer "B.Fab")
		)
		(fp_line
			(start 0.299974 -0.150114)
			(end -0.299974 -0.150114)
			(stroke
				(width 0.1)
				(type default)
			)
			(layer "B.Fab")
		)
		(fp_line
			(start 0.299974 0.150114)
			(end 0.299974 -0.150114)
			(stroke
				(width 0.1)
				(type default)
			)
			(layer "B.Fab")
		)
		(pad "1" smd rect
			(at 0.2667 0 180)
			(size 0.3048 0.381)
			(layers "B.Cu" "B.Mask" "B.Paste")
			(net "P1V8_VDDA_PEX2")
		)
		(pad "2" smd rect
			(at -0.2667 0 180)
			(size 0.3048 0.381)
			(layers "B.Cu" "B.Mask" "B.Paste")
			(net "GND")
		)
	)
)
